# T6G (Grand Teton) — schematic netlist excerpt (pin names and nets, part order shuffled) for the footprints in the layout excerpt that follows; sources: Cadence DE-HDL packaged netlist, KiCad conversion of 04192023_DAF0TMB3IC0_F0TG_MB_C_brd_V02_OCP.brd

R3831  Q_RES  0 5% CHIP  pkg 0402LF  page 140 : A = P12V_OCP_PWRGD_2 ; B = HP_LVC3_OCP_V3_2_P12V_PWRGD
C706  Q_CAP_DIFFBUS  DIFF BUS_0.22UF 6.3V 20% X6S  pkg C0201  page 67 : \1\ = P5E_CPU1_G1_TX_C_DN<1> ; \2\ = P5E_CPU1_G1_TX_DN<1>
R6065  Q_RES  0 5% EMPTY  pkg 0402LF  page 150 : A = UART_CPU0_SCM_LVC3_UART1_R1_TX ; B = UART_CPU0_SCM_LVC3_UART1_TX

(kicad_pcb
	(version 20260206)
	(generator "pcbnew")
	(generator_version "10.0")
	(general
		(thickness 1.6)
		(legacy_teardrops no)
	)
	(paper "A4")
	(title_block
		(title "04192023_DAF0TMB3IC0_F0TG_MB_C_brd_V02_OCP.brd")
		(comment 1 "Grand Teton / footprints 3638-3640 of 8354")
	)
	(layers
		(0 "F.Cu" signal "TOP")
		(4 "In1.Cu" signal "GND")
		(6 "In2.Cu" signal "IN1")
		(8 "In3.Cu" signal "GND1")
		(10 "In4.Cu" signal "IN2")
		(12 "In5.Cu" signal "GND2")
		(14 "In6.Cu" signal "IN3")
		(16 "In7.Cu" signal "GND3")
		(18 "In8.Cu" signal "VCC")
		(20 "In9.Cu" signal "VCC1")
		(22 "In10.Cu" signal "GND4")
		(24 "In11.Cu" signal "IN4")
		(26 "In12.Cu" signal "GND5")
		(28 "In13.Cu" signal "IN5")
		(30 "In14.Cu" signal "GND6")
		(32 "In15.Cu" signal "IN6")
		(34 "In16.Cu" signal "GND7")
		(2 "B.Cu" signal "BOTTOM")
		(9 "F.Adhes" user "F.Adhesive")
		(11 "B.Adhes" user "B.Adhesive")
		(13 "F.Paste" user "Package Geometry/Pastemask Top")
		(15 "B.Paste" user "Package Geometry/Pastemask Bottom")
		(5 "F.SilkS" user "Ref Des/Silkscreen Top")
		(7 "B.SilkS" user "Ref Des/Silkscreen Bottom")
		(1 "F.Mask" user "Board Geometry/Soldermask Top")
		(3 "B.Mask" user "Board Geometry/Soldermask Bottom")
		(17 "Dwgs.User" user "User.Drawings")
		(19 "Cmts.User" user "User.Comments")
		(21 "Eco1.User" user "User.Eco1")
		(23 "Eco2.User" user "User.Eco2")
		(25 "Edge.Cuts" user "Board Geometry/Outline")
		(27 "Margin" user)
		(31 "F.CrtYd" user "Package Geometry/Place Bound Top")
		(29 "B.CrtYd" user "Package Geometry/Place Bound Bottom")
		(35 "F.Fab" user "Ref Des/Assembly Top")
		(33 "B.Fab" user "Ref Des/Assembly Bottom")
	)
	(footprint ""
		(layer "F.Cu")
		(at 82.306668 -17.745202)
		(property "Reference" "R3831"
			(at 0 0 0)
			(layer "F.SilkS")
			(hide yes)
			(effects
				(font
					(size 1.27 1.27)
				)
			)
		)
		(property "Value" ""
			(at 0 0 0)
			(layer "F.Fab")
			(effects
				(font
					(size 1.27 1.27)
				)
			)
		)
		(duplicate_pad_numbers_are_jumpers no)
		(fp_line
			(start -0.7874 -0.4064)
			(end 0.7874 -0.4064)
			(stroke
				(width 0.1524)
				(type default)
			)
			(layer "F.SilkS")
		)
		(fp_line
			(start -0.7874 0.4064)
			(end -0.7874 -0.4064)
			(stroke
				(width 0.1524)
				(type default)
			)
			(layer "F.SilkS")
		)
		(fp_line
			(start 0.7874 -0.4064)
			(end 0.7874 0.4064)
			(stroke
				(width 0.1524)
				(type default)
			)
			(layer "F.SilkS")
		)
		(fp_line
			(start 0.7874 0.4064)
			(end -0.7874 0.4064)
			(stroke
				(width 0.1524)
				(type default)
			)
			(layer "F.SilkS")
		)
		(fp_line
			(start -0.67945 -0.305054)
			(end -0.12065 -0.305054)
			(stroke
				(width 0.1)
				(type default)
			)
			(layer "F.Fab")
		)
		(fp_line
			(start -0.67945 0.3048)
			(end -0.67945 -0.305054)
			(stroke
				(width 0.1)
				(type default)
			)
			(layer "F.Fab")
		)
		(fp_line
			(start -0.12065 -0.305054)
			(end -0.12065 -0.2794)
			(stroke
				(width 0.1)
				(type default)
			)
			(layer "F.Fab")
		)
		(fp_line
			(start -0.12065 -0.2794)
			(end 0.12065 -0.2794)
			(stroke
				(width 0.1)
				(type default)
			)
			(layer "F.Fab")
		)
		(fp_line
			(start -0.12065 0.2794)
			(end -0.12065 0.3048)
			(stroke
				(width 0.1)
				(type default)
			)
			(layer "F.Fab")
		)
		(fp_line
			(start -0.12065 0.3048)
			(end -0.67945 0.3048)
			(stroke
				(width 0.1)
				(type default)
			)
			(layer "F.Fab")
		)
		(fp_line
			(start 0.120396 0.2794)
			(end -0.12065 0.2794)
			(stroke
				(width 0.1)
				(type default)
			)
			(layer "F.Fab")
		)
		(fp_line
			(start 0.120396 0.3048)
			(end 0.120396 0.2794)
			(stroke
				(width 0.1)
				(type default)
			)
			(layer "F.Fab")
		)
		(fp_line
			(start 0.12065 -0.3048)
			(end 0.67945 -0.3048)
			(stroke
				(width 0.1)
				(type default)
			)
			(layer "F.Fab")
		)
		(fp_line
			(start 0.12065 -0.2794)
			(end 0.12065 -0.3048)
			(stroke
				(width 0.1)
				(type default)
			)
			(layer "F.Fab")
		)
		(fp_line
			(start 0.67945 -0.3048)
			(end 0.67945 0.3048)
			(stroke
				(width 0.1)
				(type default)
			)
			(layer "F.Fab")
		)
		(fp_line
			(start 0.67945 0.3048)
			(end 0.120396 0.3048)
			(stroke
				(width 0.1)
				(type default)
			)
			(layer "F.Fab")
		)
		(pad "1" smd circle
			(at -0.40005 0)
			(size 0 0)
			(layers "F.Cu" "F.Mask" "F.Paste")
			(net "P12V_OCP_PWRGD_2")
		)
		(pad "2" smd circle
			(at 0.40005 0)
			(size 0 0)
			(layers "F.Cu" "F.Mask" "F.Paste")
			(net "HP_LVC3_OCP_V3_2_P12V_PWRGD")
		)
	)
	(footprint ""
		(layer "F.Cu")
		(at 185.26252 -19.435572 90)
		(property "Reference" "R6065"
			(at 0 0 90)
			(layer "F.SilkS")
			(hide yes)
			(effects
				(font
					(size 1.27 1.27)
				)
			)
		)
		(property "Value" ""
			(at 0 0 90)
			(layer "F.Fab")
			(effects
				(font
					(size 1.27 1.27)
				)
			)
		)
		(duplicate_pad_numbers_are_jumpers no)
		(fp_line
			(start 0.7874 -0.4064)
			(end 0.7874 0.4064)
			(stroke
				(width 0.1524)
				(type default)
			)
			(layer "F.SilkS")
		)
		(fp_line
			(start -0.7874 -0.4064)
			(end 0.7874 -0.4064)
			(stroke
				(width 0.1524)
				(type default)
			)
			(layer "F.SilkS")
		)
		(fp_line
			(start 0.7874 0.4064)
			(end -0.7874 0.4064)
			(stroke
				(width 0.1524)
				(type default)
			)
			(layer "F.SilkS")
		)
		(fp_line
			(start -0.7874 0.4064)
			(end -0.7874 -0.4064)
			(stroke
				(width 0.1524)
				(type default)
			)
			(layer "F.SilkS")
		)
		(fp_line
			(start -0.12065 -0.305054)
			(end -0.12065 -0.2794)
			(stroke
				(width 0.1)
				(type default)
			)
			(layer "F.Fab")
		)
		(fp_line
			(start -0.67945 -0.305054)
			(end -0.12065 -0.305054)
			(stroke
				(width 0.1)
				(type default)
			)
			(layer "F.Fab")
		)
		(fp_line
			(start 0.67945 -0.3048)
			(end 0.67945 0.3048)
			(stroke
				(width 0.1)
				(type default)
			)
			(layer "F.Fab")
		)
		(fp_line
			(start 0.12065 -0.3048)
			(end 0.67945 -0.3048)
			(stroke
				(width 0.1)
				(type default)
			)
			(layer "F.Fab")
		)
		(fp_line
			(start 0.12065 -0.2794)
			(end 0.12065 -0.3048)
			(stroke
				(width 0.1)
				(type default)
			)
			(layer "F.Fab")
		)
		(fp_line
			(start -0.12065 -0.2794)
			(end 0.12065 -0.2794)
			(stroke
				(width 0.1)
				(type default)
			)
			(layer "F.Fab")
		)
		(fp_line
			(start 0.120396 0.2794)
			(end -0.12065 0.2794)
			(stroke
				(width 0.1)
				(type default)
			)
			(layer "F.Fab")
		)
		(fp_line
			(start -0.12065 0.2794)
			(end -0.12065 0.3048)
			(stroke
				(width 0.1)
				(type default)
			)
			(layer "F.Fab")
		)
		(fp_line
			(start 0.67945 0.3048)
			(end 0.120396 0.3048)
			(stroke
				(width 0.1)
				(type default)
			)
			(layer "F.Fab")
		)
		(fp_line
			(start 0.120396 0.3048)
			(end 0.120396 0.2794)
			(stroke
				(width 0.1)
				(type default)
			)
			(layer "F.Fab")
		)
		(fp_line
			(start -0.12065 0.3048)
			(end -0.67945 0.3048)
			(stroke
				(width 0.1)
				(type default)
			)
			(layer "F.Fab")
		)
		(fp_line
			(start -0.67945 0.3048)
			(end -0.67945 -0.305054)
			(stroke
				(width 0.1)
				(type default)
			)
			(layer "F.Fab")
		)
		(pad "1" smd circle
			(at -0.40005 0 90)
			(size 0 0)
			(layers "F.Cu" "F.Mask" "F.Paste")
			(net "UART_CPU0_SCM_LVC3_UART1_R1_TX")
		)
		(pad "2" smd circle
			(at 0.40005 0 90)
			(size 0 0)
			(layers "F.Cu" "F.Mask" "F.Paste")
			(net "UART_CPU0_SCM_LVC3_UART1_TX")
		)
	)
	(footprint ""
		(layer "F.Cu")
		(at 54.96433 -16.099536 90)
		(property "Reference" "C706"
			(at 0 0 90)
			(layer "F.SilkS")
			(hide yes)
			(effects
				(font
					(size 1.27 1.27)
				)
			)
		)
		(property "Value" ""
			(at 0 0 90)
			(layer "F.Fab")
			(effects
				(font
					(size 1.27 1.27)
				)
			)
		)
		(duplicate_pad_numbers_are_jumpers no)
		(fp_line
			(start 0.299974 -0.150114)
			(end 0.299974 0.150114)
			(stroke
				(width 0.1)
				(type default)
			)
			(layer "F.Fab")
		)
		(fp_line
			(start -0.299974 -0.150114)
			(end 0.299974 -0.150114)
			(stroke
				(width 0.1)
				(type default)
			)
			(layer "F.Fab")
		)
		(fp_line
			(start 0.299974 0.150114)
			(end -0.299974 0.150114)
			(stroke
				(width 0.1)
				(type default)
			)
			(layer "F.Fab")
		)
		(fp_line
			(start -0.299974 0.150114)
			(end -0.299974 -0.150114)
			(stroke
				(width 0.1)
				(type default)
			)
			(layer "F.Fab")
		)
		(pad "1" smd rect
			(at -0.2667 0 90)
			(size 0.3048 0.381)
			(layers "F.Cu" "F.Mask" "F.Paste")
			(net "P5E_CPU1_G1_TX_C_DN<1>")
		)
		(pad "2" smd rect
			(at 0.2667 0 90)
			(size 0.3048 0.381)
			(layers "F.Cu" "F.Mask" "F.Paste")
			(net "P5E_CPU1_G1_TX_DN<1>")
		)
	)
)
